(kicad_pcb
	(version 20260206)
	(generator "pcbnew")
	(generator_version "10.0")
	(general
		(thickness 1.6)
		(legacy_teardrops no)
	)
	(paper "A4")
	(title_block
		(title "Bryce Canyon_F.DPB_16315-1-OCP.brd")
		(comment 1 "Bryce Canyon / footprint 2183 of 2223 (IO2), pads 110-166 of 202")
	)
	(layers
		(0 "F.Cu" signal "TOP")
		(4 "In1.Cu" signal "L2GND")
		(6 "In2.Cu" signal "L3")
		(8 "In3.Cu" signal "L4GND")
		(10 "In4.Cu" signal "L5")
		(12 "In5.Cu" signal "L6VCC")
		(14 "In6.Cu" signal "L7VCC")
		(16 "In7.Cu" signal "L8")
		(18 "In8.Cu" signal "L9GND")
		(20 "In9.Cu" signal "L10")
		(22 "In10.Cu" signal "L11GND")
		(2 "B.Cu" signal "BOTTOM")
		(9 "F.Adhes" user "F.Adhesive")
		(11 "B.Adhes" user "B.Adhesive")
		(13 "F.Paste" user "Package Geometry/Pastemask Top")
		(15 "B.Paste" user "Package Geometry/Pastemask Bottom")
		(5 "F.SilkS" user "Ref Des/Silkscreen Top")
		(7 "B.SilkS" user "Ref Des/Silkscreen Bottom")
		(1 "F.Mask" user "Board Geometry/Soldermask Top")
		(3 "B.Mask" user "Board Geometry/Soldermask Bottom")
		(17 "Dwgs.User" user "User.Drawings")
		(19 "Cmts.User" user "User.Comments")
		(21 "Eco1.User" user "User.Eco1")
		(23 "Eco2.User" user "User.Eco2")
		(25 "Edge.Cuts" user "Board Geometry/Outline")
		(27 "Margin" user)
		(31 "F.CrtYd" user "Package Geometry/Place Bound Top")
		(29 "B.CrtYd" user "Package Geometry/Place Bound Bottom")
		(35 "F.Fab" user "Ref Des/Assembly Top")
		(33 "B.Fab" user "Ref Des/Assembly Bottom")
	)
	(footprint ""
		(layer "B.Cu")
		(at 389.349996 -30.550104 180)
		(property "Reference" "IO2"
			(at 0 0 0)
			(layer "B.SilkS")
			(hide yes)
			(effects
				(font
					(size 1.27 1.27)
				)
				(justify mirror)
			)
		)
		(property "Value" "DM-AMP-CONN200-13R-6-GP-01"
			(at 47.5488 -16.5862 180)
			(unlocked yes)
			(layer "B.Fab")
			(hide yes)
			(effects
				(font
					(size 1.016 1.016)
					(thickness 0.1524)
				)
				(justify mirror)
			)
		)
		(property "Device Type" "DMFIT-200P-384346H577-01"
			(at 47.5488 -18.1102 180)
			(unlocked yes)
			(layer "B.Fab")
			(hide yes)
			(effects
				(font
					(size 1.016 1.016)
					(thickness 0.1524)
				)
				(justify mirror)
			)
		)
		(duplicate_pad_numbers_are_jumpers no)
		(pad "G12" thru_hole circle
			(at 26.999946 -11.800078)
			(size 0.664718 0.664718)
			(drill 0.359918)
			(layers "*.Cu" "*.Mask")
			(remove_unused_layers no)
			(net "PCIE_COMP_B_TO_IOM_B_20_DN")
			(clearance 0.264414)
			(padstack
				(mode custom)
				(layer "In1.Cu"
					(shape circle)
					(size 0.664718 0.664718)
					(clearance 0.264414)
				)
				(layer "In2.Cu"
					(shape circle)
					(size 0.664718 0.664718)
					(clearance 0.264414)
				)
				(layer "In3.Cu"
					(shape circle)
					(size 0.664718 0.664718)
					(clearance 0.264414)
				)
				(layer "In4.Cu"
					(shape circle)
					(size 0.664718 0.664718)
					(clearance 0.264414)
				)
				(layer "In5.Cu"
					(shape circle)
					(size 0.664718 0.664718)
					(clearance 0.264414)
				)
				(layer "In6.Cu"
					(shape circle)
					(size 0.762 0.762)
					(clearance 0.1651)
				)
				(layer "In7.Cu"
					(shape circle)
					(size 0.762 0.762)
					(clearance 0.1651)
				)
				(layer "In8.Cu"
					(shape circle)
					(size 0.762 0.762)
					(clearance 0.1651)
				)
				(layer "In9.Cu"
					(shape circle)
					(size 0.762 0.762)
					(clearance 0.1651)
				)
				(layer "In10.Cu"
					(shape circle)
					(size 0.762 0.762)
					(clearance 0.1651)
				)
				(layer "B.Cu"
					(shape circle)
					(size 0.762 0.762)
					(thermal_gap 0.1651)
					(clearance 0.1651)
				)
			)
		)
		(pad "G13" thru_hole circle
			(at 28.800044 -10.80008)
			(size 0.664718 0.664718)
			(drill 0.359918)
			(layers "*.Cu" "*.Mask")
			(remove_unused_layers no)
			(net "PCIE_COMP_B_TO_IOM_B_19_DN")
			(clearance 0.264414)
			(padstack
				(mode custom)
				(layer "In1.Cu"
					(shape circle)
					(size 0.664718 0.664718)
					(clearance 0.264414)
				)
				(layer "In2.Cu"
					(shape circle)
					(size 0.664718 0.664718)
					(clearance 0.264414)
				)
				(layer "In3.Cu"
					(shape circle)
					(size 0.664718 0.664718)
					(clearance 0.264414)
				)
				(layer "In4.Cu"
					(shape circle)
					(size 0.664718 0.664718)
					(clearance 0.264414)
				)
				(layer "In5.Cu"
					(shape circle)
					(size 0.664718 0.664718)
					(clearance 0.264414)
				)
				(layer "In6.Cu"
					(shape circle)
					(size 0.762 0.762)
					(clearance 0.1651)
				)
				(layer "In7.Cu"
					(shape circle)
					(size 0.762 0.762)
					(clearance 0.1651)
				)
				(layer "In8.Cu"
					(shape circle)
					(size 0.762 0.762)
					(clearance 0.1651)
				)
				(layer "In9.Cu"
					(shape circle)
					(size 0.762 0.762)
					(clearance 0.1651)
				)
				(layer "In10.Cu"
					(shape circle)
					(size 0.762 0.762)
					(clearance 0.1651)
				)
				(layer "B.Cu"
					(shape circle)
					(size 0.762 0.762)
					(thermal_gap 0.1651)
					(clearance 0.1651)
				)
			)
		)
		(pad "G14" thru_hole circle
			(at 30.599888 -11.800078)
			(size 0.664718 0.664718)
			(drill 0.359918)
			(layers "*.Cu" "*.Mask")
			(remove_unused_layers no)
			(net "PCIE_COMP_B_TO_IOM_B_18_DN")
			(clearance 0.264414)
			(padstack
				(mode custom)
				(layer "In1.Cu"
					(shape circle)
					(size 0.664718 0.664718)
					(clearance 0.264414)
				)
				(layer "In2.Cu"
					(shape circle)
					(size 0.664718 0.664718)
					(clearance 0.264414)
				)
				(layer "In3.Cu"
					(shape circle)
					(size 0.664718 0.664718)
					(clearance 0.264414)
				)
				(layer "In4.Cu"
					(shape circle)
					(size 0.664718 0.664718)
					(clearance 0.264414)
				)
				(layer "In5.Cu"
					(shape circle)
					(size 0.664718 0.664718)
					(clearance 0.264414)
				)
				(layer "In6.Cu"
					(shape circle)
					(size 0.762 0.762)
					(clearance 0.1651)
				)
				(layer "In7.Cu"
					(shape circle)
					(size 0.762 0.762)
					(clearance 0.1651)
				)
				(layer "In8.Cu"
					(shape circle)
					(size 0.762 0.762)
					(clearance 0.1651)
				)
				(layer "In9.Cu"
					(shape circle)
					(size 0.762 0.762)
					(clearance 0.1651)
				)
				(layer "In10.Cu"
					(shape circle)
					(size 0.762 0.762)
					(clearance 0.1651)
				)
				(layer "B.Cu"
					(shape circle)
					(size 0.762 0.762)
					(thermal_gap 0.1651)
					(clearance 0.1651)
				)
			)
		)
		(pad "G15" thru_hole circle
			(at 32.399986 -10.80008)
			(size 0.664718 0.664718)
			(drill 0.359918)
			(layers "*.Cu" "*.Mask")
			(remove_unused_layers no)
			(net "PCIE_COMP_B_TO_IOM_B_17_DN")
			(clearance 0.264414)
			(padstack
				(mode custom)
				(layer "In1.Cu"
					(shape circle)
					(size 0.664718 0.664718)
					(clearance 0.264414)
				)
				(layer "In2.Cu"
					(shape circle)
					(size 0.664718 0.664718)
					(clearance 0.264414)
				)
				(layer "In3.Cu"
					(shape circle)
					(size 0.664718 0.664718)
					(clearance 0.264414)
				)
				(layer "In4.Cu"
					(shape circle)
					(size 0.664718 0.664718)
					(clearance 0.264414)
				)
				(layer "In5.Cu"
					(shape circle)
					(size 0.664718 0.664718)
					(clearance 0.264414)
				)
				(layer "In6.Cu"
					(shape circle)
					(size 0.762 0.762)
					(clearance 0.1651)
				)
				(layer "In7.Cu"
					(shape circle)
					(size 0.762 0.762)
					(clearance 0.1651)
				)
				(layer "In8.Cu"
					(shape circle)
					(size 0.762 0.762)
					(clearance 0.1651)
				)
				(layer "In9.Cu"
					(shape circle)
					(size 0.762 0.762)
					(clearance 0.1651)
				)
				(layer "In10.Cu"
					(shape circle)
					(size 0.762 0.762)
					(clearance 0.1651)
				)
				(layer "B.Cu"
					(shape circle)
					(size 0.762 0.762)
					(thermal_gap 0.1651)
					(clearance 0.1651)
				)
			)
		)
		(pad "G16" thru_hole circle
			(at 34.200084 -11.800078)
			(size 0.664718 0.664718)
			(drill 0.359918)
			(layers "*.Cu" "*.Mask")
			(remove_unused_layers no)
			(net "PCIE_COMP_B_TO_IOM_B_16_DN")
			(clearance 0.264414)
			(padstack
				(mode custom)
				(layer "In1.Cu"
					(shape circle)
					(size 0.664718 0.664718)
					(clearance 0.264414)
				)
				(layer "In2.Cu"
					(shape circle)
					(size 0.664718 0.664718)
					(clearance 0.264414)
				)
				(layer "In3.Cu"
					(shape circle)
					(size 0.664718 0.664718)
					(clearance 0.264414)
				)
				(layer "In4.Cu"
					(shape circle)
					(size 0.664718 0.664718)
					(clearance 0.264414)
				)
				(layer "In5.Cu"
					(shape circle)
					(size 0.664718 0.664718)
					(clearance 0.264414)
				)
				(layer "In6.Cu"
					(shape circle)
					(size 0.762 0.762)
					(clearance 0.1651)
				)
				(layer "In7.Cu"
					(shape circle)
					(size 0.762 0.762)
					(clearance 0.1651)
				)
				(layer "In8.Cu"
					(shape circle)
					(size 0.762 0.762)
					(clearance 0.1651)
				)
				(layer "In9.Cu"
					(shape circle)
					(size 0.762 0.762)
					(clearance 0.1651)
				)
				(layer "In10.Cu"
					(shape circle)
					(size 0.762 0.762)
					(clearance 0.1651)
				)
				(layer "B.Cu"
					(shape circle)
					(size 0.762 0.762)
					(thermal_gap 0.1651)
					(clearance 0.1651)
				)
			)
		)
		(pad "GND1" thru_hole circle
			(at 0 -2.500122)
			(size 0.762 0.762)
			(drill 0.359918)
			(layers "*.Cu" "*.Mask")
			(remove_unused_layers no)
			(net "GND")
			(clearance 0.1651)
			(thermal_gap 0.1651)
		)
		(pad "GND2" thru_hole circle
			(at 0 -6.100064)
			(size 0.762 0.762)
			(drill 0.359918)
			(layers "*.Cu" "*.Mask")
			(remove_unused_layers no)
			(net "GND")
			(clearance 0.1651)
			(thermal_gap 0.1651)
		)
		(pad "GND3" thru_hole circle
			(at 0 -9.700006)
			(size 0.762 0.762)
			(drill 0.359918)
			(layers "*.Cu" "*.Mask")
			(remove_unused_layers no)
			(net "GND")
			(clearance 0.1651)
			(thermal_gap 0.1651)
		)
		(pad "GND4" thru_hole circle
			(at 0 -13.299948)
			(size 0.762 0.762)
			(drill 0.359918)
			(layers "*.Cu" "*.Mask")
			(remove_unused_layers no)
			(net "GND")
			(clearance 0.1651)
			(thermal_gap 0.1651)
		)
		(pad "GND5" thru_hole circle
			(at 1.800098 0.100076)
			(size 0.762 0.762)
			(drill 0.359918)
			(layers "*.Cu" "*.Mask")
			(remove_unused_layers no)
			(net "GND")
			(clearance 0.1651)
			(thermal_gap 0.1651)
		)
		(pad "GND6" thru_hole circle
			(at 1.800098 -3.50012)
			(size 0.762 0.762)
			(drill 0.359918)
			(layers "*.Cu" "*.Mask")
			(remove_unused_layers no)
			(net "GND")
			(clearance 0.1651)
			(thermal_gap 0.1651)
		)
		(pad "GND7" thru_hole circle
			(at 1.800098 -7.100062)
			(size 0.762 0.762)
			(drill 0.359918)
			(layers "*.Cu" "*.Mask")
			(remove_unused_layers no)
			(net "GND")
			(clearance 0.1651)
			(thermal_gap 0.1651)
		)
		(pad "GND8" thru_hole circle
			(at 1.800098 -10.700004)
			(size 0.762 0.762)
			(drill 0.359918)
			(layers "*.Cu" "*.Mask")
			(remove_unused_layers no)
			(net "GND")
			(clearance 0.1651)
			(thermal_gap 0.1651)
		)
		(pad "GND9" thru_hole circle
			(at 1.800098 -14.299946)
			(size 0.762 0.762)
			(drill 0.359918)
			(layers "*.Cu" "*.Mask")
			(remove_unused_layers no)
			(net "GND")
			(clearance 0.1651)
			(thermal_gap 0.1651)
		)
		(pad "GND10" thru_hole circle
			(at 3.599942 -2.500122)
			(size 0.762 0.762)
			(drill 0.359918)
			(layers "*.Cu" "*.Mask")
			(remove_unused_layers no)
			(net "GND")
			(clearance 0.1651)
			(thermal_gap 0.1651)
		)
		(pad "GND11" thru_hole circle
			(at 3.599942 -6.100064)
			(size 0.762 0.762)
			(drill 0.359918)
			(layers "*.Cu" "*.Mask")
			(remove_unused_layers no)
			(net "GND")
			(clearance 0.1651)
			(thermal_gap 0.1651)
		)
		(pad "GND12" thru_hole circle
			(at 3.599942 -9.700006)
			(size 0.762 0.762)
			(drill 0.359918)
			(layers "*.Cu" "*.Mask")
			(remove_unused_layers no)
			(net "GND")
			(clearance 0.1651)
			(thermal_gap 0.1651)
		)
		(pad "GND13" thru_hole circle
			(at 3.599942 -13.299948)
			(size 0.762 0.762)
			(drill 0.359918)
			(layers "*.Cu" "*.Mask")
			(remove_unused_layers no)
			(net "GND")
			(clearance 0.1651)
			(thermal_gap 0.1651)
		)
		(pad "GND14" thru_hole circle
			(at 5.40004 0.100076)
			(size 0.762 0.762)
			(drill 0.359918)
			(layers "*.Cu" "*.Mask")
			(remove_unused_layers no)
			(net "GND")
			(clearance 0.1651)
			(thermal_gap 0.1651)
		)
		(pad "GND15" thru_hole circle
			(at 5.40004 -3.50012)
			(size 0.762 0.762)
			(drill 0.359918)
			(layers "*.Cu" "*.Mask")
			(remove_unused_layers no)
			(net "GND")
			(clearance 0.1651)
			(thermal_gap 0.1651)
		)
		(pad "GND16" thru_hole circle
			(at 5.40004 -7.100062)
			(size 0.762 0.762)
			(drill 0.359918)
			(layers "*.Cu" "*.Mask")
			(remove_unused_layers no)
			(net "GND")
			(clearance 0.1651)
			(thermal_gap 0.1651)
		)
		(pad "GND17" thru_hole circle
			(at 5.40004 -10.700004)
			(size 0.762 0.762)
			(drill 0.359918)
			(layers "*.Cu" "*.Mask")
			(remove_unused_layers no)
			(net "GND")
			(clearance 0.1651)
			(thermal_gap 0.1651)
		)
		(pad "GND18" thru_hole circle
			(at 5.40004 -14.299946)
			(size 0.762 0.762)
			(drill 0.359918)
			(layers "*.Cu" "*.Mask")
			(remove_unused_layers no)
			(net "GND")
			(clearance 0.1651)
			(thermal_gap 0.1651)
		)
		(pad "GND19" thru_hole circle
			(at 7.199884 -2.500122)
			(size 0.762 0.762)
			(drill 0.359918)
			(layers "*.Cu" "*.Mask")
			(remove_unused_layers no)
			(net "GND")
			(clearance 0.1651)
			(thermal_gap 0.1651)
		)
		(pad "GND20" thru_hole circle
			(at 7.199884 -6.100064)
			(size 0.762 0.762)
			(drill 0.359918)
			(layers "*.Cu" "*.Mask")
			(remove_unused_layers no)
			(net "GND")
			(clearance 0.1651)
			(thermal_gap 0.1651)
		)
		(pad "GND21" thru_hole circle
			(at 7.199884 -9.700006)
			(size 0.762 0.762)
			(drill 0.359918)
			(layers "*.Cu" "*.Mask")
			(remove_unused_layers no)
			(net "GND")
			(clearance 0.1651)
			(thermal_gap 0.1651)
		)
		(pad "GND22" thru_hole circle
			(at 7.199884 -13.299948)
			(size 0.762 0.762)
			(drill 0.359918)
			(layers "*.Cu" "*.Mask")
			(remove_unused_layers no)
			(net "GND")
			(clearance 0.1651)
			(thermal_gap 0.1651)
		)
		(pad "GND23" thru_hole circle
			(at 8.999982 0.100076)
			(size 0.762 0.762)
			(drill 0.359918)
			(layers "*.Cu" "*.Mask")
			(remove_unused_layers no)
			(net "GND")
			(clearance 0.1651)
			(thermal_gap 0.1651)
		)
		(pad "GND24" thru_hole circle
			(at 8.999982 -3.50012)
			(size 0.762 0.762)
			(drill 0.359918)
			(layers "*.Cu" "*.Mask")
			(remove_unused_layers no)
			(net "GND")
			(clearance 0.1651)
			(thermal_gap 0.1651)
		)
		(pad "GND25" thru_hole circle
			(at 8.999982 -7.100062)
			(size 0.762 0.762)
			(drill 0.359918)
			(layers "*.Cu" "*.Mask")
			(remove_unused_layers no)
			(net "GND")
			(clearance 0.1651)
			(thermal_gap 0.1651)
		)
		(pad "GND26" thru_hole circle
			(at 8.999982 -10.700004)
			(size 0.762 0.762)
			(drill 0.359918)
			(layers "*.Cu" "*.Mask")
			(remove_unused_layers no)
			(net "GND")
			(clearance 0.1651)
			(thermal_gap 0.1651)
		)
		(pad "GND27" thru_hole circle
			(at 8.999982 -14.299946)
			(size 0.762 0.762)
			(drill 0.359918)
			(layers "*.Cu" "*.Mask")
			(remove_unused_layers no)
			(net "GND")
			(clearance 0.1651)
			(thermal_gap 0.1651)
		)
		(pad "GND28" thru_hole circle
			(at 10.80008 -2.500122)
			(size 0.762 0.762)
			(drill 0.359918)
			(layers "*.Cu" "*.Mask")
			(remove_unused_layers no)
			(net "GND")
			(clearance 0.1651)
			(thermal_gap 0.1651)
		)
		(pad "GND29" thru_hole circle
			(at 10.80008 -6.100064)
			(size 0.762 0.762)
			(drill 0.359918)
			(layers "*.Cu" "*.Mask")
			(remove_unused_layers no)
			(net "GND")
			(clearance 0.1651)
			(thermal_gap 0.1651)
		)
		(pad "GND30" thru_hole circle
			(at 10.80008 -9.700006)
			(size 0.762 0.762)
			(drill 0.359918)
			(layers "*.Cu" "*.Mask")
			(remove_unused_layers no)
			(net "GND")
			(clearance 0.1651)
			(thermal_gap 0.1651)
		)
		(pad "GND31" thru_hole circle
			(at 10.80008 -13.299948)
			(size 0.762 0.762)
			(drill 0.359918)
			(layers "*.Cu" "*.Mask")
			(remove_unused_layers no)
			(net "GND")
			(clearance 0.1651)
			(thermal_gap 0.1651)
		)
		(pad "GND32" thru_hole circle
			(at 12.599924 0.100076)
			(size 0.762 0.762)
			(drill 0.359918)
			(layers "*.Cu" "*.Mask")
			(remove_unused_layers no)
			(net "GND")
			(clearance 0.1651)
			(thermal_gap 0.1651)
		)
		(pad "GND33" thru_hole circle
			(at 12.599924 -3.50012)
			(size 0.762 0.762)
			(drill 0.359918)
			(layers "*.Cu" "*.Mask")
			(remove_unused_layers no)
			(net "GND")
			(clearance 0.1651)
			(thermal_gap 0.1651)
		)
		(pad "GND34" thru_hole circle
			(at 12.599924 -7.100062)
			(size 0.762 0.762)
			(drill 0.359918)
			(layers "*.Cu" "*.Mask")
			(remove_unused_layers no)
			(net "GND")
			(clearance 0.1651)
			(thermal_gap 0.1651)
		)
		(pad "GND35" thru_hole circle
			(at 12.599924 -10.700004)
			(size 0.762 0.762)
			(drill 0.359918)
			(layers "*.Cu" "*.Mask")
			(remove_unused_layers no)
			(net "GND")
			(clearance 0.1651)
			(thermal_gap 0.1651)
		)
		(pad "GND36" thru_hole circle
			(at 12.599924 -14.299946)
			(size 0.762 0.762)
			(drill 0.359918)
			(layers "*.Cu" "*.Mask")
			(remove_unused_layers no)
			(net "GND")
			(clearance 0.1651)
			(thermal_gap 0.1651)
		)
		(pad "GND37" thru_hole circle
			(at 21.599906 -2.500122)
			(size 0.762 0.762)
			(drill 0.359918)
			(layers "*.Cu" "*.Mask")
			(remove_unused_layers no)
			(net "GND")
			(clearance 0.1651)
			(thermal_gap 0.1651)
		)
		(pad "GND38" thru_hole circle
			(at 21.599906 -6.100064)
			(size 0.762 0.762)
			(drill 0.359918)
			(layers "*.Cu" "*.Mask")
			(remove_unused_layers no)
			(net "GND")
			(clearance 0.1651)
			(thermal_gap 0.1651)
		)
		(pad "GND39" thru_hole circle
			(at 21.599906 -9.700006)
			(size 0.762 0.762)
			(drill 0.359918)
			(layers "*.Cu" "*.Mask")
			(remove_unused_layers no)
			(net "GND")
			(clearance 0.1651)
			(thermal_gap 0.1651)
		)
		(pad "GND40" thru_hole circle
			(at 21.599906 -13.299948)
			(size 0.762 0.762)
			(drill 0.359918)
			(layers "*.Cu" "*.Mask")
			(remove_unused_layers no)
			(net "GND")
			(clearance 0.1651)
			(thermal_gap 0.1651)
		)
		(pad "GND41" thru_hole circle
			(at 23.400004 0.100076)
			(size 0.762 0.762)
			(drill 0.359918)
			(layers "*.Cu" "*.Mask")
			(remove_unused_layers no)
			(net "GND")
			(clearance 0.1651)
			(thermal_gap 0.1651)
		)
		(pad "GND42" thru_hole circle
			(at 23.400004 -3.50012)
			(size 0.762 0.762)
			(drill 0.359918)
			(layers "*.Cu" "*.Mask")
			(remove_unused_layers no)
			(net "GND")
			(clearance 0.1651)
			(thermal_gap 0.1651)
		)
		(pad "GND43" thru_hole circle
			(at 23.400004 -7.100062)
			(size 0.762 0.762)
			(drill 0.359918)
			(layers "*.Cu" "*.Mask")
			(remove_unused_layers no)
			(net "GND")
			(clearance 0.1651)
			(thermal_gap 0.1651)
		)
		(pad "GND44" thru_hole circle
			(at 23.400004 -10.700004)
			(size 0.762 0.762)
			(drill 0.359918)
			(layers "*.Cu" "*.Mask")
			(remove_unused_layers no)
			(net "GND")
			(clearance 0.1651)
			(thermal_gap 0.1651)
		)
		(pad "GND45" thru_hole circle
			(at 23.400004 -14.299946)
			(size 0.762 0.762)
			(drill 0.359918)
			(layers "*.Cu" "*.Mask")
			(remove_unused_layers no)
			(net "GND")
			(clearance 0.1651)
			(thermal_gap 0.1651)
		)
		(pad "GND46" thru_hole circle
			(at 25.200102 -2.500122)
			(size 0.762 0.762)
			(drill 0.359918)
			(layers "*.Cu" "*.Mask")
			(remove_unused_layers no)
			(net "GND")
			(clearance 0.1651)
			(thermal_gap 0.1651)
		)
		(pad "GND47" thru_hole circle
			(at 25.200102 -6.100064)
			(size 0.762 0.762)
			(drill 0.359918)
			(layers "*.Cu" "*.Mask")
			(remove_unused_layers no)
			(net "GND")
			(clearance 0.1651)
			(thermal_gap 0.1651)
		)
		(pad "GND48" thru_hole circle
			(at 25.200102 -9.700006)
			(size 0.762 0.762)
			(drill 0.359918)
			(layers "*.Cu" "*.Mask")
			(remove_unused_layers no)
			(net "GND")
			(clearance 0.1651)
			(thermal_gap 0.1651)
		)
		(pad "GND49" thru_hole circle
			(at 25.200102 -13.299948)
			(size 0.762 0.762)
			(drill 0.359918)
			(layers "*.Cu" "*.Mask")
			(remove_unused_layers no)
			(net "GND")
			(clearance 0.1651)
			(thermal_gap 0.1651)
		)
		(pad "GND50" thru_hole circle
			(at 26.999946 0.100076)
			(size 0.762 0.762)
			(drill 0.359918)
			(layers "*.Cu" "*.Mask")
			(remove_unused_layers no)
			(net "GND")
			(clearance 0.1651)
			(thermal_gap 0.1651)
		)
		(pad "GND51" thru_hole circle
			(at 26.999946 -3.50012)
			(size 0.762 0.762)
			(drill 0.359918)
			(layers "*.Cu" "*.Mask")
			(remove_unused_layers no)
			(net "GND")
			(clearance 0.1651)
			(thermal_gap 0.1651)
		)
		(pad "GND52" thru_hole circle
			(at 26.999946 -7.100062)
			(size 0.762 0.762)
			(drill 0.359918)
			(layers "*.Cu" "*.Mask")
			(remove_unused_layers no)
			(net "GND")
			(clearance 0.1651)
			(thermal_gap 0.1651)
		)
	)
)
